# T6G (Grand Teton) — schematic netlist excerpt (pin names and nets, part order shuffled) for the footprints in the layout excerpt that follows; sources: Cadence DE-HDL packaged netlist, KiCad conversion of 04192023_DAF0TMB3IC0_F0TG_MB_C_brd_V02_OCP.brd

C103  Q_CAP  100UF 4V 20% X6S  pkg C0805  page 334 : A = P1V8_CPU1_RT1_1A ; B = GND
C2032  Q_CAP  0.1UF 25V 10% X7R  pkg 0402  page 234 : A = P3V3_AUX_USB_HUB ; B = GND
R3  Q_RES  2K 1% CHIP  pkg 0402LF  page 83 : A = RST_PERST_CPU1_SWB_1_N ; B = GND

(kicad_pcb
	(version 20260206)
	(generator "pcbnew")
	(generator_version "10.0")
	(general
		(thickness 1.6)
		(legacy_teardrops no)
	)
	(paper "A4")
	(title_block
		(title "04192023_DAF0TMB3IC0_F0TG_MB_C_brd_V02_OCP.brd")
		(comment 1 "Grand Teton / footprints 6384-6386 of 8354")
	)
	(layers
		(0 "F.Cu" signal "TOP")
		(4 "In1.Cu" signal "GND")
		(6 "In2.Cu" signal "IN1")
		(8 "In3.Cu" signal "GND1")
		(10 "In4.Cu" signal "IN2")
		(12 "In5.Cu" signal "GND2")
		(14 "In6.Cu" signal "IN3")
		(16 "In7.Cu" signal "GND3")
		(18 "In8.Cu" signal "VCC")
		(20 "In9.Cu" signal "VCC1")
		(22 "In10.Cu" signal "GND4")
		(24 "In11.Cu" signal "IN4")
		(26 "In12.Cu" signal "GND5")
		(28 "In13.Cu" signal "IN5")
		(30 "In14.Cu" signal "GND6")
		(32 "In15.Cu" signal "IN6")
		(34 "In16.Cu" signal "GND7")
		(2 "B.Cu" signal "BOTTOM")
		(9 "F.Adhes" user "F.Adhesive")
		(11 "B.Adhes" user "B.Adhesive")
		(13 "F.Paste" user "Package Geometry/Pastemask Top")
		(15 "B.Paste" user "Package Geometry/Pastemask Bottom")
		(5 "F.SilkS" user "Ref Des/Silkscreen Top")
		(7 "B.SilkS" user "Ref Des/Silkscreen Bottom")
		(1 "F.Mask" user "Board Geometry/Soldermask Top")
		(3 "B.Mask" user "Board Geometry/Soldermask Bottom")
		(17 "Dwgs.User" user "User.Drawings")
		(19 "Cmts.User" user "User.Comments")
		(21 "Eco1.User" user "User.Eco1")
		(23 "Eco2.User" user "User.Eco2")
		(25 "Edge.Cuts" user "Board Geometry/Outline")
		(27 "Margin" user)
		(31 "F.CrtYd" user "Package Geometry/Place Bound Top")
		(29 "B.CrtYd" user "Package Geometry/Place Bound Bottom")
		(35 "F.Fab" user "Ref Des/Assembly Top")
		(33 "B.Fab" user "Ref Des/Assembly Bottom")
	)
	(footprint ""
		(layer "B.Cu")
		(at 201.12355 -116.971572 180)
		(property "Reference" "R3"
			(at 0 0 0)
			(layer "B.SilkS")
			(hide yes)
			(effects
				(font
					(size 1.27 1.27)
				)
				(justify mirror)
			)
		)
		(property "Value" ""
			(at 0 0 0)
			(layer "B.Fab")
			(effects
				(font
					(size 1.27 1.27)
				)
				(justify mirror)
			)
		)
		(duplicate_pad_numbers_are_jumpers no)
		(fp_line
			(start 0.7874 0.4064)
			(end 0.7874 -0.4064)
			(stroke
				(width 0.1524)
				(type default)
			)
			(layer "B.SilkS")
		)
		(fp_line
			(start 0.7874 -0.4064)
			(end -0.7874 -0.4064)
			(stroke
				(width 0.1524)
				(type default)
			)
			(layer "B.SilkS")
		)
		(fp_line
			(start -0.7874 0.4064)
			(end 0.7874 0.4064)
			(stroke
				(width 0.1524)
				(type default)
			)
			(layer "B.SilkS")
		)
		(fp_line
			(start -0.7874 -0.4064)
			(end -0.7874 0.4064)
			(stroke
				(width 0.1524)
				(type default)
			)
			(layer "B.SilkS")
		)
		(fp_line
			(start 0.67945 0.3048)
			(end 0.67945 -0.305054)
			(stroke
				(width 0.1)
				(type default)
			)
			(layer "B.Fab")
		)
		(fp_line
			(start 0.67945 -0.305054)
			(end 0.12065 -0.305054)
			(stroke
				(width 0.1)
				(type default)
			)
			(layer "B.Fab")
		)
		(fp_line
			(start 0.12065 0.3048)
			(end 0.67945 0.3048)
			(stroke
				(width 0.1)
				(type default)
			)
			(layer "B.Fab")
		)
		(fp_line
			(start 0.12065 0.2794)
			(end 0.12065 0.3048)
			(stroke
				(width 0.1)
				(type default)
			)
			(layer "B.Fab")
		)
		(fp_line
			(start 0.12065 -0.2794)
			(end -0.12065 -0.2794)
			(stroke
				(width 0.1)
				(type default)
			)
			(layer "B.Fab")
		)
		(fp_line
			(start 0.12065 -0.305054)
			(end 0.12065 -0.2794)
			(stroke
				(width 0.1)
				(type default)
			)
			(layer "B.Fab")
		)
		(fp_line
			(start -0.120396 0.3048)
			(end -0.120396 0.2794)
			(stroke
				(width 0.1)
				(type default)
			)
			(layer "B.Fab")
		)
		(fp_line
			(start -0.120396 0.2794)
			(end 0.12065 0.2794)
			(stroke
				(width 0.1)
				(type default)
			)
			(layer "B.Fab")
		)
		(fp_line
			(start -0.12065 -0.2794)
			(end -0.12065 -0.3048)
			(stroke
				(width 0.1)
				(type default)
			)
			(layer "B.Fab")
		)
		(fp_line
			(start -0.12065 -0.3048)
			(end -0.67945 -0.3048)
			(stroke
				(width 0.1)
				(type default)
			)
			(layer "B.Fab")
		)
		(fp_line
			(start -0.67945 0.3048)
			(end -0.120396 0.3048)
			(stroke
				(width 0.1)
				(type default)
			)
			(layer "B.Fab")
		)
		(fp_line
			(start -0.67945 -0.3048)
			(end -0.67945 0.3048)
			(stroke
				(width 0.1)
				(type default)
			)
			(layer "B.Fab")
		)
		(pad "1" smd circle
			(at 0.40005 0)
			(size 0 0)
			(layers "B.Cu" "B.Mask" "B.Paste")
			(net "RST_PERST_CPU1_SWB_1_N")
		)
		(pad "2" smd circle
			(at -0.40005 0)
			(size 0 0)
			(layers "B.Cu" "B.Mask" "B.Paste")
			(net "GND")
		)
	)
	(footprint ""
		(layer "B.Cu")
		(at 16.208502 -98.669348)
		(property "Reference" "C2032"
			(at 0 0 0)
			(layer "B.SilkS")
			(hide yes)
			(effects
				(font
					(size 1.27 1.27)
				)
				(justify mirror)
			)
		)
		(property "Value" ""
			(at 0 0 0)
			(layer "B.Fab")
			(effects
				(font
					(size 1.27 1.27)
				)
				(justify mirror)
			)
		)
		(duplicate_pad_numbers_are_jumpers no)
		(fp_line
			(start -0.7874 -0.4064)
			(end -0.7874 0.4064)
			(stroke
				(width 0.1524)
				(type default)
			)
			(layer "B.SilkS")
		)
		(fp_line
			(start -0.7874 0.4064)
			(end 0.7874 0.4064)
			(stroke
				(width 0.1524)
				(type default)
			)
			(layer "B.SilkS")
		)
		(fp_line
			(start 0.7874 -0.4064)
			(end -0.7874 -0.4064)
			(stroke
				(width 0.1524)
				(type default)
			)
			(layer "B.SilkS")
		)
		(fp_line
			(start 0.7874 0.4064)
			(end 0.7874 -0.4064)
			(stroke
				(width 0.1524)
				(type default)
			)
			(layer "B.SilkS")
		)
		(fp_line
			(start -0.67945 -0.3048)
			(end -0.67945 0.3048)
			(stroke
				(width 0.1)
				(type default)
			)
			(layer "B.Fab")
		)
		(fp_line
			(start -0.67945 0.3048)
			(end -0.120396 0.3048)
			(stroke
				(width 0.1)
				(type default)
			)
			(layer "B.Fab")
		)
		(fp_line
			(start -0.12065 -0.3048)
			(end -0.67945 -0.3048)
			(stroke
				(width 0.1)
				(type default)
			)
			(layer "B.Fab")
		)
		(fp_line
			(start -0.12065 -0.2794)
			(end -0.12065 -0.3048)
			(stroke
				(width 0.1)
				(type default)
			)
			(layer "B.Fab")
		)
		(fp_line
			(start -0.120396 0.2794)
			(end 0.12065 0.2794)
			(stroke
				(width 0.1)
				(type default)
			)
			(layer "B.Fab")
		)
		(fp_line
			(start -0.120396 0.3048)
			(end -0.120396 0.2794)
			(stroke
				(width 0.1)
				(type default)
			)
			(layer "B.Fab")
		)
		(fp_line
			(start 0.12065 -0.305054)
			(end 0.12065 -0.2794)
			(stroke
				(width 0.1)
				(type default)
			)
			(layer "B.Fab")
		)
		(fp_line
			(start 0.12065 -0.2794)
			(end -0.12065 -0.2794)
			(stroke
				(width 0.1)
				(type default)
			)
			(layer "B.Fab")
		)
		(fp_line
			(start 0.12065 0.2794)
			(end 0.12065 0.3048)
			(stroke
				(width 0.1)
				(type default)
			)
			(layer "B.Fab")
		)
		(fp_line
			(start 0.12065 0.3048)
			(end 0.67945 0.3048)
			(stroke
				(width 0.1)
				(type default)
			)
			(layer "B.Fab")
		)
		(fp_line
			(start 0.67945 -0.305054)
			(end 0.12065 -0.305054)
			(stroke
				(width 0.1)
				(type default)
			)
			(layer "B.Fab")
		)
		(fp_line
			(start 0.67945 0.3048)
			(end 0.67945 -0.305054)
			(stroke
				(width 0.1)
				(type default)
			)
			(layer "B.Fab")
		)
		(pad "1" smd circle
			(at 0.40005 0 180)
			(size 0 0)
			(layers "B.Cu" "B.Mask" "B.Paste")
			(net "P3V3_AUX_USB_HUB")
		)
		(pad "2" smd circle
			(at -0.40005 0 180)
			(size 0 0)
			(layers "B.Cu" "B.Mask" "B.Paste")
			(net "GND")
		)
	)
	(footprint ""
		(layer "B.Cu")
		(at 101.444044 -387.084062 -90)
		(property "Reference" "C103"
			(at 0 0 90)
			(layer "B.SilkS")
			(hide yes)
			(effects
				(font
					(size 1.27 1.27)
				)
				(justify mirror)
			)
		)
		(property "Value" ""
			(at 0 0 90)
			(layer "B.Fab")
			(effects
				(font
					(size 1.27 1.27)
				)
				(justify mirror)
			)
		)
		(duplicate_pad_numbers_are_jumpers no)
		(fp_line
			(start -1.524 0.762)
			(end 1.524 0.762)
			(stroke
				(width 0.1524)
				(type default)
			)
			(layer "B.SilkS")
		)
		(fp_line
			(start 1.524 0.762)
			(end 1.524 -0.762)
			(stroke
				(width 0.1524)
				(type default)
			)
			(layer "B.SilkS")
		)
		(fp_line
			(start -1.524 -0.762)
			(end -1.524 0.762)
			(stroke
				(width 0.1524)
				(type default)
			)
			(layer "B.SilkS")
		)
		(fp_line
			(start 1.524 -0.762)
			(end -1.524 -0.762)
			(stroke
				(width 0.1524)
				(type default)
			)
			(layer "B.SilkS")
		)
		(fp_line
			(start -1.1049 0.724916)
			(end -1.1049 -0.724916)
			(stroke
				(width 0.1)
				(type default)
			)
			(layer "B.Fab")
		)
		(fp_line
			(start 1.1049 0.724916)
			(end -1.1049 0.724916)
			(stroke
				(width 0.1)
				(type default)
			)
			(layer "B.Fab")
		)
		(fp_line
			(start -1.1049 -0.724916)
			(end 1.1049 -0.724916)
			(stroke
				(width 0.1)
				(type default)
			)
			(layer "B.Fab")
		)
		(fp_line
			(start 1.1049 -0.724916)
			(end 1.1049 0.724916)
			(stroke
				(width 0.1)
				(type default)
			)
			(layer "B.Fab")
		)
		(pad "1" smd rect
			(at 0.889 0 270)
			(size 1.016 1.27)
			(layers "B.Cu" "B.Mask" "B.Paste")
			(net "P1V8_CPU1_RT1_1A")
		)
		(pad "2" smd rect
			(at -0.889 0 270)
			(size 1.016 1.27)
			(layers "B.Cu" "B.Mask" "B.Paste")
			(net "GND")
		)
	)
)
